# T6G (Grand Teton) — schematic netlist excerpt (pin names and nets, part order shuffled) for the footprints in the layout excerpt that follows; sources: Cadence DE-HDL packaged netlist, KiCad conversion of 04192023_DAF0TMB3IC0_F0TG_MB_C_brd_V02_OCP.brd

R370  Q_RES  1K 1% CHIP  pkg 0402LF  page 161 : A = PVDD18_S5_P0 ; B = SMB_CPU0_SEC_SDA
C582  Q_CAP  0.1UF 10V 10% X7S  pkg C0201  page 279 : A = P0V9_CPU0_RT0_2A ; B = GND
C2483  Q_CAP  22UF 4V 20% X6S  pkg C0402  page 74 : A = PVDD11_S3_P1 ; B = GND

(kicad_pcb
	(version 20260206)
	(generator "pcbnew")
	(generator_version "10.0")
	(general
		(thickness 1.6)
		(legacy_teardrops no)
	)
	(paper "A4")
	(title_block
		(title "04192023_DAF0TMB3IC0_F0TG_MB_C_brd_V02_OCP.brd")
		(comment 1 "Grand Teton / footprints 8179-8181 of 8354")
	)
	(layers
		(0 "F.Cu" signal "TOP")
		(4 "In1.Cu" signal "GND")
		(6 "In2.Cu" signal "IN1")
		(8 "In3.Cu" signal "GND1")
		(10 "In4.Cu" signal "IN2")
		(12 "In5.Cu" signal "GND2")
		(14 "In6.Cu" signal "IN3")
		(16 "In7.Cu" signal "GND3")
		(18 "In8.Cu" signal "VCC")
		(20 "In9.Cu" signal "VCC1")
		(22 "In10.Cu" signal "GND4")
		(24 "In11.Cu" signal "IN4")
		(26 "In12.Cu" signal "GND5")
		(28 "In13.Cu" signal "IN5")
		(30 "In14.Cu" signal "GND6")
		(32 "In15.Cu" signal "IN6")
		(34 "In16.Cu" signal "GND7")
		(2 "B.Cu" signal "BOTTOM")
		(9 "F.Adhes" user "F.Adhesive")
		(11 "B.Adhes" user "B.Adhesive")
		(13 "F.Paste" user "Package Geometry/Pastemask Top")
		(15 "B.Paste" user "Package Geometry/Pastemask Bottom")
		(5 "F.SilkS" user "Ref Des/Silkscreen Top")
		(7 "B.SilkS" user "Ref Des/Silkscreen Bottom")
		(1 "F.Mask" user "Board Geometry/Soldermask Top")
		(3 "B.Mask" user "Board Geometry/Soldermask Bottom")
		(17 "Dwgs.User" user "User.Drawings")
		(19 "Cmts.User" user "User.Comments")
		(21 "Eco1.User" user "User.Eco1")
		(23 "Eco2.User" user "User.Eco2")
		(25 "Edge.Cuts" user "Board Geometry/Outline")
		(27 "Margin" user)
		(31 "F.CrtYd" user "Package Geometry/Place Bound Top")
		(29 "B.CrtYd" user "Package Geometry/Place Bound Bottom")
		(35 "F.Fab" user "Ref Des/Assembly Top")
		(33 "B.Fab" user "Ref Des/Assembly Bottom")
	)
	(footprint ""
		(layer "B.Cu")
		(at 123.357386 -264.354564)
		(property "Reference" "C2483"
			(at 0 0 0)
			(layer "B.SilkS")
			(hide yes)
			(effects
				(font
					(size 1.27 1.27)
				)
				(justify mirror)
			)
		)
		(property "Value" ""
			(at 0 0 0)
			(layer "B.Fab")
			(effects
				(font
					(size 1.27 1.27)
				)
				(justify mirror)
			)
		)
		(duplicate_pad_numbers_are_jumpers no)
		(fp_line
			(start -0.7874 -0.4064)
			(end -0.7874 0.4064)
			(stroke
				(width 0.1524)
				(type default)
			)
			(layer "B.SilkS")
		)
		(fp_line
			(start -0.7874 0.4064)
			(end 0.7874 0.4064)
			(stroke
				(width 0.1524)
				(type default)
			)
			(layer "B.SilkS")
		)
		(fp_line
			(start 0.7874 -0.4064)
			(end -0.7874 -0.4064)
			(stroke
				(width 0.1524)
				(type default)
			)
			(layer "B.SilkS")
		)
		(fp_line
			(start 0.7874 0.4064)
			(end 0.7874 -0.4064)
			(stroke
				(width 0.1524)
				(type default)
			)
			(layer "B.SilkS")
		)
		(fp_line
			(start -0.67945 -0.3048)
			(end -0.67945 0.3048)
			(stroke
				(width 0.1)
				(type default)
			)
			(layer "B.Fab")
		)
		(fp_line
			(start -0.67945 0.3048)
			(end -0.120396 0.3048)
			(stroke
				(width 0.1)
				(type default)
			)
			(layer "B.Fab")
		)
		(fp_line
			(start -0.12065 -0.3048)
			(end -0.67945 -0.3048)
			(stroke
				(width 0.1)
				(type default)
			)
			(layer "B.Fab")
		)
		(fp_line
			(start -0.12065 -0.2794)
			(end -0.12065 -0.3048)
			(stroke
				(width 0.1)
				(type default)
			)
			(layer "B.Fab")
		)
		(fp_line
			(start -0.120396 0.2794)
			(end 0.12065 0.2794)
			(stroke
				(width 0.1)
				(type default)
			)
			(layer "B.Fab")
		)
		(fp_line
			(start -0.120396 0.3048)
			(end -0.120396 0.2794)
			(stroke
				(width 0.1)
				(type default)
			)
			(layer "B.Fab")
		)
		(fp_line
			(start 0.12065 -0.305054)
			(end 0.12065 -0.2794)
			(stroke
				(width 0.1)
				(type default)
			)
			(layer "B.Fab")
		)
		(fp_line
			(start 0.12065 -0.2794)
			(end -0.12065 -0.2794)
			(stroke
				(width 0.1)
				(type default)
			)
			(layer "B.Fab")
		)
		(fp_line
			(start 0.12065 0.2794)
			(end 0.12065 0.3048)
			(stroke
				(width 0.1)
				(type default)
			)
			(layer "B.Fab")
		)
		(fp_line
			(start 0.12065 0.3048)
			(end 0.67945 0.3048)
			(stroke
				(width 0.1)
				(type default)
			)
			(layer "B.Fab")
		)
		(fp_line
			(start 0.67945 -0.305054)
			(end 0.12065 -0.305054)
			(stroke
				(width 0.1)
				(type default)
			)
			(layer "B.Fab")
		)
		(fp_line
			(start 0.67945 0.3048)
			(end 0.67945 -0.305054)
			(stroke
				(width 0.1)
				(type default)
			)
			(layer "B.Fab")
		)
		(pad "1" smd circle
			(at 0.40005 0 180)
			(size 0 0)
			(layers "B.Cu" "B.Mask" "B.Paste")
			(net "PVDD11_S3_P1")
		)
		(pad "2" smd circle
			(at -0.40005 0 180)
			(size 0 0)
			(layers "B.Cu" "B.Mask" "B.Paste")
			(net "GND")
		)
	)
	(footprint ""
		(layer "B.Cu")
		(at 319.118234 -396.393162 -90)
		(property "Reference" "C582"
			(at 0 0 90)
			(layer "B.SilkS")
			(hide yes)
			(effects
				(font
					(size 1.27 1.27)
				)
				(justify mirror)
			)
		)
		(property "Value" ""
			(at 0 0 90)
			(layer "B.Fab")
			(effects
				(font
					(size 1.27 1.27)
				)
				(justify mirror)
			)
		)
		(duplicate_pad_numbers_are_jumpers no)
		(fp_line
			(start -0.299974 0.150114)
			(end 0.299974 0.150114)
			(stroke
				(width 0.1)
				(type default)
			)
			(layer "B.Fab")
		)
		(fp_line
			(start 0.299974 0.150114)
			(end 0.299974 -0.150114)
			(stroke
				(width 0.1)
				(type default)
			)
			(layer "B.Fab")
		)
		(fp_line
			(start -0.299974 -0.150114)
			(end -0.299974 0.150114)
			(stroke
				(width 0.1)
				(type default)
			)
			(layer "B.Fab")
		)
		(fp_line
			(start 0.299974 -0.150114)
			(end -0.299974 -0.150114)
			(stroke
				(width 0.1)
				(type default)
			)
			(layer "B.Fab")
		)
		(pad "1" smd rect
			(at 0.2667 0 90)
			(size 0.3048 0.381)
			(layers "B.Cu" "B.Mask" "B.Paste")
			(net "P0V9_CPU0_RT0_2A")
		)
		(pad "2" smd rect
			(at -0.2667 0 90)
			(size 0.3048 0.381)
			(layers "B.Cu" "B.Mask" "B.Paste")
			(net "GND")
		)
	)
	(footprint ""
		(layer "B.Cu")
		(at 240.411 -231.648 -90)
		(property "Reference" "R370"
			(at 0 0 90)
			(layer "B.SilkS")
			(hide yes)
			(effects
				(font
					(size 1.27 1.27)
				)
				(justify mirror)
			)
		)
		(property "Value" ""
			(at 0 0 90)
			(layer "B.Fab")
			(effects
				(font
					(size 1.27 1.27)
				)
				(justify mirror)
			)
		)
		(duplicate_pad_numbers_are_jumpers no)
		(fp_line
			(start -0.7874 0.4064)
			(end 0.7874 0.4064)
			(stroke
				(width 0.1524)
				(type default)
			)
			(layer "B.SilkS")
		)
		(fp_line
			(start 0.7874 0.4064)
			(end 0.7874 -0.4064)
			(stroke
				(width 0.1524)
				(type default)
			)
			(layer "B.SilkS")
		)
		(fp_line
			(start -0.7874 -0.4064)
			(end -0.7874 0.4064)
			(stroke
				(width 0.1524)
				(type default)
			)
			(layer "B.SilkS")
		)
		(fp_line
			(start 0.7874 -0.4064)
			(end -0.7874 -0.4064)
			(stroke
				(width 0.1524)
				(type default)
			)
			(layer "B.SilkS")
		)
		(fp_line
			(start -0.67945 0.3048)
			(end -0.120396 0.3048)
			(stroke
				(width 0.1)
				(type default)
			)
			(layer "B.Fab")
		)
		(fp_line
			(start -0.120396 0.3048)
			(end -0.120396 0.2794)
			(stroke
				(width 0.1)
				(type default)
			)
			(layer "B.Fab")
		)
		(fp_line
			(start 0.12065 0.3048)
			(end 0.67945 0.3048)
			(stroke
				(width 0.1)
				(type default)
			)
			(layer "B.Fab")
		)
		(fp_line
			(start 0.67945 0.3048)
			(end 0.67945 -0.305054)
			(stroke
				(width 0.1)
				(type default)
			)
			(layer "B.Fab")
		)
		(fp_line
			(start -0.120396 0.2794)
			(end 0.12065 0.2794)
			(stroke
				(width 0.1)
				(type default)
			)
			(layer "B.Fab")
		)
		(fp_line
			(start 0.12065 0.2794)
			(end 0.12065 0.3048)
			(stroke
				(width 0.1)
				(type default)
			)
			(layer "B.Fab")
		)
		(fp_line
			(start -0.12065 -0.2794)
			(end -0.12065 -0.3048)
			(stroke
				(width 0.1)
				(type default)
			)
			(layer "B.Fab")
		)
		(fp_line
			(start 0.12065 -0.2794)
			(end -0.12065 -0.2794)
			(stroke
				(width 0.1)
				(type default)
			)
			(layer "B.Fab")
		)
		(fp_line
			(start -0.67945 -0.3048)
			(end -0.67945 0.3048)
			(stroke
				(width 0.1)
				(type default)
			)
			(layer "B.Fab")
		)
		(fp_line
			(start -0.12065 -0.3048)
			(end -0.67945 -0.3048)
			(stroke
				(width 0.1)
				(type default)
			)
			(layer "B.Fab")
		)
		(fp_line
			(start 0.12065 -0.305054)
			(end 0.12065 -0.2794)
			(stroke
				(width 0.1)
				(type default)
			)
			(layer "B.Fab")
		)
		(fp_line
			(start 0.67945 -0.305054)
			(end 0.12065 -0.305054)
			(stroke
				(width 0.1)
				(type default)
			)
			(layer "B.Fab")
		)
		(pad "1" smd circle
			(at 0.40005 0 90)
			(size 0 0)
			(layers "B.Cu" "B.Mask" "B.Paste")
			(net "PVDD18_S5_P0")
		)
		(pad "2" smd circle
			(at -0.40005 0 90)
			(size 0 0)
			(layers "B.Cu" "B.Mask" "B.Paste")
			(net "SMB_CPU0_SEC_SDA")
		)
	)
)
